(kicad_pcb
	(version 20260206)
	(generator "pcbnew")
	(generator_version "10.0")
	(general
		(thickness 1.6)
		(legacy_teardrops no)
	)
	(paper "A4")
	(title_block
		(title "9052_F0T_PDB_Converter_Brick_F_V03_1208_1600_OCP.brd")
		(comment 1 "Grand Teton / footprints 469-474 of 578")
	)
	(layers
		(0 "F.Cu" signal "TOP")
		(4 "In1.Cu" signal "GND")
		(6 "In2.Cu" signal "IN1")
		(8 "In3.Cu" signal "GND1")
		(10 "In4.Cu" signal "VCC")
		(12 "In5.Cu" signal "VCC1")
		(14 "In6.Cu" signal "GND2")
		(16 "In7.Cu" signal "IN2")
		(18 "In8.Cu" signal "GND3")
		(2 "B.Cu" signal "BOTTOM")
		(9 "F.Adhes" user "F.Adhesive")
		(11 "B.Adhes" user "B.Adhesive")
		(13 "F.Paste" user "Package Geometry/Pastemask Top")
		(15 "B.Paste" user "Package Geometry/Pastemask Bottom")
		(5 "F.SilkS" user "Ref Des/Silkscreen Top")
		(7 "B.SilkS" user "Ref Des/Silkscreen Bottom")
		(1 "F.Mask" user "Board Geometry/Soldermask Top")
		(3 "B.Mask" user "Board Geometry/Soldermask Bottom")
		(17 "Dwgs.User" user "User.Drawings")
		(19 "Cmts.User" user "User.Comments")
		(21 "Eco1.User" user "User.Eco1")
		(23 "Eco2.User" user "User.Eco2")
		(25 "Edge.Cuts" user "Board Geometry/Outline")
		(27 "Margin" user)
		(31 "F.CrtYd" user "Package Geometry/Place Bound Top")
		(29 "B.CrtYd" user "Package Geometry/Place Bound Bottom")
		(35 "F.Fab" user "Ref Des/Assembly Top")
		(33 "B.Fab" user "Ref Des/Assembly Bottom")
	)
	(footprint ""
		(layer "B.Cu")
		(at 212.344 -82.169)
		(property "Reference" "R188"
			(at 0 0 0)
			(layer "B.SilkS")
			(hide yes)
			(effects
				(font
					(size 1.27 1.27)
				)
				(justify mirror)
			)
		)
		(property "Value" ""
			(at 0 0 0)
			(layer "B.Fab")
			(effects
				(font
					(size 1.27 1.27)
				)
				(justify mirror)
			)
		)
		(duplicate_pad_numbers_are_jumpers no)
		(fp_line
			(start -0.7874 -0.4064)
			(end -0.7874 0.4064)
			(stroke
				(width 0.1524)
				(type default)
			)
			(layer "B.SilkS")
		)
		(fp_line
			(start -0.7874 0.4064)
			(end 0.7874 0.4064)
			(stroke
				(width 0.1524)
				(type default)
			)
			(layer "B.SilkS")
		)
		(fp_line
			(start 0.7874 -0.4064)
			(end -0.7874 -0.4064)
			(stroke
				(width 0.1524)
				(type default)
			)
			(layer "B.SilkS")
		)
		(fp_line
			(start 0.7874 0.4064)
			(end 0.7874 -0.4064)
			(stroke
				(width 0.1524)
				(type default)
			)
			(layer "B.SilkS")
		)
		(fp_line
			(start -0.67945 -0.3048)
			(end -0.67945 0.3048)
			(stroke
				(width 0.1)
				(type default)
			)
			(layer "B.Fab")
		)
		(fp_line
			(start -0.67945 0.3048)
			(end -0.120396 0.3048)
			(stroke
				(width 0.1)
				(type default)
			)
			(layer "B.Fab")
		)
		(fp_line
			(start -0.12065 -0.3048)
			(end -0.67945 -0.3048)
			(stroke
				(width 0.1)
				(type default)
			)
			(layer "B.Fab")
		)
		(fp_line
			(start -0.12065 -0.2794)
			(end -0.12065 -0.3048)
			(stroke
				(width 0.1)
				(type default)
			)
			(layer "B.Fab")
		)
		(fp_line
			(start -0.120396 0.2794)
			(end 0.12065 0.2794)
			(stroke
				(width 0.1)
				(type default)
			)
			(layer "B.Fab")
		)
		(fp_line
			(start -0.120396 0.3048)
			(end -0.120396 0.2794)
			(stroke
				(width 0.1)
				(type default)
			)
			(layer "B.Fab")
		)
		(fp_line
			(start 0.12065 -0.305054)
			(end 0.12065 -0.2794)
			(stroke
				(width 0.1)
				(type default)
			)
			(layer "B.Fab")
		)
		(fp_line
			(start 0.12065 -0.2794)
			(end -0.12065 -0.2794)
			(stroke
				(width 0.1)
				(type default)
			)
			(layer "B.Fab")
		)
		(fp_line
			(start 0.12065 0.2794)
			(end 0.12065 0.3048)
			(stroke
				(width 0.1)
				(type default)
			)
			(layer "B.Fab")
		)
		(fp_line
			(start 0.12065 0.3048)
			(end 0.67945 0.3048)
			(stroke
				(width 0.1)
				(type default)
			)
			(layer "B.Fab")
		)
		(fp_line
			(start 0.67945 -0.305054)
			(end 0.12065 -0.305054)
			(stroke
				(width 0.1)
				(type default)
			)
			(layer "B.Fab")
		)
		(fp_line
			(start 0.67945 0.3048)
			(end 0.67945 -0.305054)
			(stroke
				(width 0.1)
				(type default)
			)
			(layer "B.Fab")
		)
		(pad "1" smd circle
			(at 0.40005 0 180)
			(size 0 0)
			(layers "B.Cu" "B.Mask" "B.Paste")
			(net "GND")
		)
		(pad "2" smd circle
			(at -0.40005 0 180)
			(size 0 0)
			(layers "B.Cu" "B.Mask" "B.Paste")
			(net "PWRGD_GPU_HSC")
		)
	)
	(footprint ""
		(layer "B.Cu")
		(at 109.732826 -115.824 -90)
		(property "Reference" "C74"
			(at 0 0 90)
			(layer "B.SilkS")
			(hide yes)
			(effects
				(font
					(size 1.27 1.27)
				)
				(justify mirror)
			)
		)
		(property "Value" ""
			(at 0 0 90)
			(layer "B.Fab")
			(effects
				(font
					(size 1.27 1.27)
				)
				(justify mirror)
			)
		)
		(duplicate_pad_numbers_are_jumpers no)
		(fp_line
			(start -0.7874 0.4064)
			(end 0.7874 0.4064)
			(stroke
				(width 0.1524)
				(type default)
			)
			(layer "B.SilkS")
		)
		(fp_line
			(start 0.7874 0.4064)
			(end 0.7874 -0.4064)
			(stroke
				(width 0.1524)
				(type default)
			)
			(layer "B.SilkS")
		)
		(fp_line
			(start -0.7874 -0.4064)
			(end -0.7874 0.4064)
			(stroke
				(width 0.1524)
				(type default)
			)
			(layer "B.SilkS")
		)
		(fp_line
			(start 0.7874 -0.4064)
			(end -0.7874 -0.4064)
			(stroke
				(width 0.1524)
				(type default)
			)
			(layer "B.SilkS")
		)
		(fp_line
			(start -0.67945 0.3048)
			(end -0.120396 0.3048)
			(stroke
				(width 0.1)
				(type default)
			)
			(layer "B.Fab")
		)
		(fp_line
			(start -0.120396 0.3048)
			(end -0.120396 0.2794)
			(stroke
				(width 0.1)
				(type default)
			)
			(layer "B.Fab")
		)
		(fp_line
			(start 0.12065 0.3048)
			(end 0.67945 0.3048)
			(stroke
				(width 0.1)
				(type default)
			)
			(layer "B.Fab")
		)
		(fp_line
			(start 0.67945 0.3048)
			(end 0.67945 -0.305054)
			(stroke
				(width 0.1)
				(type default)
			)
			(layer "B.Fab")
		)
		(fp_line
			(start -0.120396 0.2794)
			(end 0.12065 0.2794)
			(stroke
				(width 0.1)
				(type default)
			)
			(layer "B.Fab")
		)
		(fp_line
			(start 0.12065 0.2794)
			(end 0.12065 0.3048)
			(stroke
				(width 0.1)
				(type default)
			)
			(layer "B.Fab")
		)
		(fp_line
			(start -0.12065 -0.2794)
			(end -0.12065 -0.3048)
			(stroke
				(width 0.1)
				(type default)
			)
			(layer "B.Fab")
		)
		(fp_line
			(start 0.12065 -0.2794)
			(end -0.12065 -0.2794)
			(stroke
				(width 0.1)
				(type default)
			)
			(layer "B.Fab")
		)
		(fp_line
			(start -0.67945 -0.3048)
			(end -0.67945 0.3048)
			(stroke
				(width 0.1)
				(type default)
			)
			(layer "B.Fab")
		)
		(fp_line
			(start -0.12065 -0.3048)
			(end -0.67945 -0.3048)
			(stroke
				(width 0.1)
				(type default)
			)
			(layer "B.Fab")
		)
		(fp_line
			(start 0.12065 -0.305054)
			(end 0.12065 -0.2794)
			(stroke
				(width 0.1)
				(type default)
			)
			(layer "B.Fab")
		)
		(fp_line
			(start 0.67945 -0.305054)
			(end 0.12065 -0.305054)
			(stroke
				(width 0.1)
				(type default)
			)
			(layer "B.Fab")
		)
		(pad "1" smd circle
			(at 0.40005 0 90)
			(size 0 0)
			(layers "B.Cu" "B.Mask" "B.Paste")
			(net "GND")
		)
		(pad "2" smd circle
			(at -0.40005 0 90)
			(size 0 0)
			(layers "B.Cu" "B.Mask" "B.Paste")
			(net "P12V_BRICK0_PWRGD")
		)
	)
	(footprint ""
		(layer "B.Cu")
		(at 134.493 -78.867)
		(property "Reference" "R163"
			(at 0 0 0)
			(layer "B.SilkS")
			(hide yes)
			(effects
				(font
					(size 1.27 1.27)
				)
				(justify mirror)
			)
		)
		(property "Value" ""
			(at 0 0 0)
			(layer "B.Fab")
			(effects
				(font
					(size 1.27 1.27)
				)
				(justify mirror)
			)
		)
		(duplicate_pad_numbers_are_jumpers no)
		(fp_line
			(start -0.7874 -0.4064)
			(end -0.7874 0.4064)
			(stroke
				(width 0.1524)
				(type default)
			)
			(layer "B.SilkS")
		)
		(fp_line
			(start -0.7874 0.4064)
			(end 0.7874 0.4064)
			(stroke
				(width 0.1524)
				(type default)
			)
			(layer "B.SilkS")
		)
		(fp_line
			(start 0.7874 -0.4064)
			(end -0.7874 -0.4064)
			(stroke
				(width 0.1524)
				(type default)
			)
			(layer "B.SilkS")
		)
		(fp_line
			(start 0.7874 0.4064)
			(end 0.7874 -0.4064)
			(stroke
				(width 0.1524)
				(type default)
			)
			(layer "B.SilkS")
		)
		(fp_line
			(start -0.67945 -0.3048)
			(end -0.67945 0.3048)
			(stroke
				(width 0.1)
				(type default)
			)
			(layer "B.Fab")
		)
		(fp_line
			(start -0.67945 0.3048)
			(end -0.120396 0.3048)
			(stroke
				(width 0.1)
				(type default)
			)
			(layer "B.Fab")
		)
		(fp_line
			(start -0.12065 -0.3048)
			(end -0.67945 -0.3048)
			(stroke
				(width 0.1)
				(type default)
			)
			(layer "B.Fab")
		)
		(fp_line
			(start -0.12065 -0.2794)
			(end -0.12065 -0.3048)
			(stroke
				(width 0.1)
				(type default)
			)
			(layer "B.Fab")
		)
		(fp_line
			(start -0.120396 0.2794)
			(end 0.12065 0.2794)
			(stroke
				(width 0.1)
				(type default)
			)
			(layer "B.Fab")
		)
		(fp_line
			(start -0.120396 0.3048)
			(end -0.120396 0.2794)
			(stroke
				(width 0.1)
				(type default)
			)
			(layer "B.Fab")
		)
		(fp_line
			(start 0.12065 -0.305054)
			(end 0.12065 -0.2794)
			(stroke
				(width 0.1)
				(type default)
			)
			(layer "B.Fab")
		)
		(fp_line
			(start 0.12065 -0.2794)
			(end -0.12065 -0.2794)
			(stroke
				(width 0.1)
				(type default)
			)
			(layer "B.Fab")
		)
		(fp_line
			(start 0.12065 0.2794)
			(end 0.12065 0.3048)
			(stroke
				(width 0.1)
				(type default)
			)
			(layer "B.Fab")
		)
		(fp_line
			(start 0.12065 0.3048)
			(end 0.67945 0.3048)
			(stroke
				(width 0.1)
				(type default)
			)
			(layer "B.Fab")
		)
		(fp_line
			(start 0.67945 -0.305054)
			(end 0.12065 -0.305054)
			(stroke
				(width 0.1)
				(type default)
			)
			(layer "B.Fab")
		)
		(fp_line
			(start 0.67945 0.3048)
			(end 0.67945 -0.305054)
			(stroke
				(width 0.1)
				(type default)
			)
			(layer "B.Fab")
		)
		(pad "1" smd circle
			(at 0.40005 0 180)
			(size 0 0)
			(layers "B.Cu" "B.Mask" "B.Paste")
			(net "P3V3_AUX")
		)
		(pad "2" smd circle
			(at -0.40005 0 180)
			(size 0 0)
			(layers "B.Cu" "B.Mask" "B.Paste")
			(net "SMB_P52V_VPDB_SDA")
		)
	)
	(footprint ""
		(layer "B.Cu")
		(at 136.85012 -116.078 -90)
		(property "Reference" "R160"
			(at 0 0 90)
			(layer "B.SilkS")
			(hide yes)
			(effects
				(font
					(size 1.27 1.27)
				)
				(justify mirror)
			)
		)
		(property "Value" ""
			(at 0 0 90)
			(layer "B.Fab")
			(effects
				(font
					(size 1.27 1.27)
				)
				(justify mirror)
			)
		)
		(duplicate_pad_numbers_are_jumpers no)
		(fp_line
			(start -0.7874 0.4064)
			(end 0.7874 0.4064)
			(stroke
				(width 0.1524)
				(type default)
			)
			(layer "B.SilkS")
		)
		(fp_line
			(start 0.7874 0.4064)
			(end 0.7874 -0.4064)
			(stroke
				(width 0.1524)
				(type default)
			)
			(layer "B.SilkS")
		)
		(fp_line
			(start -0.7874 -0.4064)
			(end -0.7874 0.4064)
			(stroke
				(width 0.1524)
				(type default)
			)
			(layer "B.SilkS")
		)
		(fp_line
			(start 0.7874 -0.4064)
			(end -0.7874 -0.4064)
			(stroke
				(width 0.1524)
				(type default)
			)
			(layer "B.SilkS")
		)
		(fp_line
			(start -0.67945 0.3048)
			(end -0.120396 0.3048)
			(stroke
				(width 0.1)
				(type default)
			)
			(layer "B.Fab")
		)
		(fp_line
			(start -0.120396 0.3048)
			(end -0.120396 0.2794)
			(stroke
				(width 0.1)
				(type default)
			)
			(layer "B.Fab")
		)
		(fp_line
			(start 0.12065 0.3048)
			(end 0.67945 0.3048)
			(stroke
				(width 0.1)
				(type default)
			)
			(layer "B.Fab")
		)
		(fp_line
			(start 0.67945 0.3048)
			(end 0.67945 -0.305054)
			(stroke
				(width 0.1)
				(type default)
			)
			(layer "B.Fab")
		)
		(fp_line
			(start -0.120396 0.2794)
			(end 0.12065 0.2794)
			(stroke
				(width 0.1)
				(type default)
			)
			(layer "B.Fab")
		)
		(fp_line
			(start 0.12065 0.2794)
			(end 0.12065 0.3048)
			(stroke
				(width 0.1)
				(type default)
			)
			(layer "B.Fab")
		)
		(fp_line
			(start -0.12065 -0.2794)
			(end -0.12065 -0.3048)
			(stroke
				(width 0.1)
				(type default)
			)
			(layer "B.Fab")
		)
		(fp_line
			(start 0.12065 -0.2794)
			(end -0.12065 -0.2794)
			(stroke
				(width 0.1)
				(type default)
			)
			(layer "B.Fab")
		)
		(fp_line
			(start -0.67945 -0.3048)
			(end -0.67945 0.3048)
			(stroke
				(width 0.1)
				(type default)
			)
			(layer "B.Fab")
		)
		(fp_line
			(start -0.12065 -0.3048)
			(end -0.67945 -0.3048)
			(stroke
				(width 0.1)
				(type default)
			)
			(layer "B.Fab")
		)
		(fp_line
			(start 0.12065 -0.305054)
			(end 0.12065 -0.2794)
			(stroke
				(width 0.1)
				(type default)
			)
			(layer "B.Fab")
		)
		(fp_line
			(start 0.67945 -0.305054)
			(end 0.12065 -0.305054)
			(stroke
				(width 0.1)
				(type default)
			)
			(layer "B.Fab")
		)
		(pad "1" smd circle
			(at 0.40005 0 90)
			(size 0 0)
			(layers "B.Cu" "B.Mask" "B.Paste")
			(net "BRICK_P12V0_EN_N")
		)
		(pad "2" smd circle
			(at -0.40005 0 90)
			(size 0 0)
			(layers "B.Cu" "B.Mask" "B.Paste")
			(net "BRICK_P12V0_ON_OFF_R")
		)
	)
	(footprint ""
		(layer "B.Cu")
		(at 237.031784 -79.72679 90)
		(property "Reference" "C1"
			(at 0 0 90)
			(layer "B.SilkS")
			(hide yes)
			(effects
				(font
					(size 1.27 1.27)
				)
				(justify mirror)
			)
		)
		(property "Value" ""
			(at 0 0 90)
			(layer "B.Fab")
			(effects
				(font
					(size 1.27 1.27)
				)
				(justify mirror)
			)
		)
		(duplicate_pad_numbers_are_jumpers no)
		(fp_line
			(start 0.7874 -0.4064)
			(end -0.7874 -0.4064)
			(stroke
				(width 0.1524)
				(type default)
			)
			(layer "B.SilkS")
		)
		(fp_line
			(start -0.7874 -0.4064)
			(end -0.7874 0.4064)
			(stroke
				(width 0.1524)
				(type default)
			)
			(layer "B.SilkS")
		)
		(fp_line
			(start 0.7874 0.4064)
			(end 0.7874 -0.4064)
			(stroke
				(width 0.1524)
				(type default)
			)
			(layer "B.SilkS")
		)
		(fp_line
			(start -0.7874 0.4064)
			(end 0.7874 0.4064)
			(stroke
				(width 0.1524)
				(type default)
			)
			(layer "B.SilkS")
		)
		(fp_line
			(start 0.67945 -0.305054)
			(end 0.12065 -0.305054)
			(stroke
				(width 0.1)
				(type default)
			)
			(layer "B.Fab")
		)
		(fp_line
			(start 0.12065 -0.305054)
			(end 0.12065 -0.2794)
			(stroke
				(width 0.1)
				(type default)
			)
			(layer "B.Fab")
		)
		(fp_line
			(start -0.12065 -0.3048)
			(end -0.67945 -0.3048)
			(stroke
				(width 0.1)
				(type default)
			)
			(layer "B.Fab")
		)
		(fp_line
			(start -0.67945 -0.3048)
			(end -0.67945 0.3048)
			(stroke
				(width 0.1)
				(type default)
			)
			(layer "B.Fab")
		)
		(fp_line
			(start 0.12065 -0.2794)
			(end -0.12065 -0.2794)
			(stroke
				(width 0.1)
				(type default)
			)
			(layer "B.Fab")
		)
		(fp_line
			(start -0.12065 -0.2794)
			(end -0.12065 -0.3048)
			(stroke
				(width 0.1)
				(type default)
			)
			(layer "B.Fab")
		)
		(fp_line
			(start 0.12065 0.2794)
			(end 0.12065 0.3048)
			(stroke
				(width 0.1)
				(type default)
			)
			(layer "B.Fab")
		)
		(fp_line
			(start -0.120396 0.2794)
			(end 0.12065 0.2794)
			(stroke
				(width 0.1)
				(type default)
			)
			(layer "B.Fab")
		)
		(fp_line
			(start 0.67945 0.3048)
			(end 0.67945 -0.305054)
			(stroke
				(width 0.1)
				(type default)
			)
			(layer "B.Fab")
		)
		(fp_line
			(start 0.12065 0.3048)
			(end 0.67945 0.3048)
			(stroke
				(width 0.1)
				(type default)
			)
			(layer "B.Fab")
		)
		(fp_line
			(start -0.120396 0.3048)
			(end -0.120396 0.2794)
			(stroke
				(width 0.1)
				(type default)
			)
			(layer "B.Fab")
		)
		(fp_line
			(start -0.67945 0.3048)
			(end -0.120396 0.3048)
			(stroke
				(width 0.1)
				(type default)
			)
			(layer "B.Fab")
		)
		(pad "1" smd circle
			(at 0.40005 0 270)
			(size 0 0)
			(layers "B.Cu" "B.Mask" "B.Paste")
			(net "P3V3_AUX")
		)
		(pad "2" smd circle
			(at -0.40005 0 270)
			(size 0 0)
			(layers "B.Cu" "B.Mask" "B.Paste")
			(net "GND")
		)
	)
	(footprint ""
		(layer "B.Cu")
		(at 52.850034 -76.708 -90)
		(property "Reference" "PR79"
			(at 0 0 90)
			(layer "B.SilkS")
			(hide yes)
			(effects
				(font
					(size 1.27 1.27)
				)
				(justify mirror)
			)
		)
		(property "Value" ""
			(at 0 0 90)
			(layer "B.Fab")
			(effects
				(font
					(size 1.27 1.27)
				)
				(justify mirror)
			)
		)
		(duplicate_pad_numbers_are_jumpers no)
		(fp_line
			(start -0.7874 0.4064)
			(end 0.7874 0.4064)
			(stroke
				(width 0.1524)
				(type default)
			)
			(layer "B.SilkS")
		)
		(fp_line
			(start 0.7874 0.4064)
			(end 0.7874 -0.4064)
			(stroke
				(width 0.1524)
				(type default)
			)
			(layer "B.SilkS")
		)
		(fp_line
			(start -0.7874 -0.4064)
			(end -0.7874 0.4064)
			(stroke
				(width 0.1524)
				(type default)
			)
			(layer "B.SilkS")
		)
		(fp_line
			(start 0.7874 -0.4064)
			(end -0.7874 -0.4064)
			(stroke
				(width 0.1524)
				(type default)
			)
			(layer "B.SilkS")
		)
		(fp_line
			(start -0.67945 0.3048)
			(end -0.120396 0.3048)
			(stroke
				(width 0.1)
				(type default)
			)
			(layer "B.Fab")
		)
		(fp_line
			(start -0.120396 0.3048)
			(end -0.120396 0.2794)
			(stroke
				(width 0.1)
				(type default)
			)
			(layer "B.Fab")
		)
		(fp_line
			(start 0.12065 0.3048)
			(end 0.67945 0.3048)
			(stroke
				(width 0.1)
				(type default)
			)
			(layer "B.Fab")
		)
		(fp_line
			(start 0.67945 0.3048)
			(end 0.67945 -0.305054)
			(stroke
				(width 0.1)
				(type default)
			)
			(layer "B.Fab")
		)
		(fp_line
			(start -0.120396 0.2794)
			(end 0.12065 0.2794)
			(stroke
				(width 0.1)
				(type default)
			)
			(layer "B.Fab")
		)
		(fp_line
			(start 0.12065 0.2794)
			(end 0.12065 0.3048)
			(stroke
				(width 0.1)
				(type default)
			)
			(layer "B.Fab")
		)
		(fp_line
			(start -0.12065 -0.2794)
			(end -0.12065 -0.3048)
			(stroke
				(width 0.1)
				(type default)
			)
			(layer "B.Fab")
		)
		(fp_line
			(start 0.12065 -0.2794)
			(end -0.12065 -0.2794)
			(stroke
				(width 0.1)
				(type default)
			)
			(layer "B.Fab")
		)
		(fp_line
			(start -0.67945 -0.3048)
			(end -0.67945 0.3048)
			(stroke
				(width 0.1)
				(type default)
			)
			(layer "B.Fab")
		)
		(fp_line
			(start -0.12065 -0.3048)
			(end -0.67945 -0.3048)
			(stroke
				(width 0.1)
				(type default)
			)
			(layer "B.Fab")
		)
		(fp_line
			(start 0.12065 -0.305054)
			(end 0.12065 -0.2794)
			(stroke
				(width 0.1)
				(type default)
			)
			(layer "B.Fab")
		)
		(fp_line
			(start 0.67945 -0.305054)
			(end 0.12065 -0.305054)
			(stroke
				(width 0.1)
				(type default)
			)
			(layer "B.Fab")
		)
		(pad "1" smd circle
			(at 0.40005 0 90)
			(size 0 0)
			(layers "B.Cu" "B.Mask" "B.Paste")
			(net "P12V_MB3_SENSE-")
		)
		(pad "2" smd circle
			(at -0.40005 0 90)
			(size 0 0)
			(layers "B.Cu" "B.Mask" "B.Paste")
			(net "GND")
		)
	)
)
